# S9S_MB_2U (Grand Teton) — schematic netlist excerpt (pin names and nets, part order shuffled) for the footprints in the layout excerpt that follows; sources: Cadence DE-HDL packaged netlist, KiCad conversion of 03242023_DA0F0TMBIJ0_F0T_Motherboard_J_brd_V01_OCP.brd

R1493  Q_RES  1K 1% CHIP  pkg 0402LF  page 215 : A = P3V3_AUX ; B = PU_FORCE_PWRON

U96  NX3L2267GM  IC  pkg XQFN10  page 239
  \1y0\  = JTAG_BMC_PLD_TDI
  \1y1\  = JTAG_BMC_DBP_TDI
  \2y0\  = JTAG_BMC_PLD_TDO
  \2y1\  = JTAG_BMC_DBP_TDO
  GND  = GND
  \2z\  = JTAG_BMC_SW_TDO
  \2s\  = FM_JTAG_BMC_MUX_SEL
  \1s\  = FM_JTAG_BMC_MUX_SEL
  \1z\  = JTAG_BMC_SW_TDI
  VCC  = P3V3_AUX

(kicad_pcb
	(version 20260206)
	(generator "pcbnew")
	(generator_version "10.0")
	(general
		(thickness 1.6)
		(legacy_teardrops no)
	)
	(paper "A4")
	(title_block
		(title "03242023_DA0F0TMBIJ0_F0T_Motherboard_J_brd_V01_OCP.brd")
		(comment 1 "Grand Teton / footprints 3389-3390 of 6105")
	)
	(layers
		(0 "F.Cu" signal "TOP")
		(4 "In1.Cu" signal "GND")
		(6 "In2.Cu" signal "IN1")
		(8 "In3.Cu" signal "GND1")
		(10 "In4.Cu" signal "IN2")
		(12 "In5.Cu" signal "GND2")
		(14 "In6.Cu" signal "IN3")
		(16 "In7.Cu" signal "GND3")
		(18 "In8.Cu" signal "VCC")
		(20 "In9.Cu" signal "VCC1")
		(22 "In10.Cu" signal "GND4")
		(24 "In11.Cu" signal "IN4")
		(26 "In12.Cu" signal "GND5")
		(28 "In13.Cu" signal "IN5")
		(30 "In14.Cu" signal "GND6")
		(32 "In15.Cu" signal "IN6")
		(34 "In16.Cu" signal "GND7")
		(2 "B.Cu" signal "BOTTOM")
		(9 "F.Adhes" user "F.Adhesive")
		(11 "B.Adhes" user "B.Adhesive")
		(13 "F.Paste" user "Package Geometry/Pastemask Top")
		(15 "B.Paste" user "Package Geometry/Pastemask Bottom")
		(5 "F.SilkS" user "Ref Des/Silkscreen Top")
		(7 "B.SilkS" user "Ref Des/Silkscreen Bottom")
		(1 "F.Mask" user "Board Geometry/Soldermask Top")
		(3 "B.Mask" user "Board Geometry/Soldermask Bottom")
		(17 "Dwgs.User" user "User.Drawings")
		(19 "Cmts.User" user "User.Comments")
		(21 "Eco1.User" user "User.Eco1")
		(23 "Eco2.User" user "User.Eco2")
		(25 "Edge.Cuts" user "Board Geometry/Outline")
		(27 "Margin" user)
		(31 "F.CrtYd" user "Package Geometry/Place Bound Top")
		(29 "B.CrtYd" user "Package Geometry/Place Bound Bottom")
		(35 "F.Fab" user "Ref Des/Assembly Top")
		(33 "B.Fab" user "Ref Des/Assembly Bottom")
	)
	(footprint ""
		(layer "F.Cu")
		(at 127.288544 -77.571092 180)
		(property "Reference" "U96"
			(at -0.257556 3.718306 0)
			(unlocked yes)
			(layer "F.SilkS")
			(effects
				(font
					(size 0.7874 0.5842)
					(thickness 0.1524)
				)
				(justify left)
			)
		)
		(property "Value" ""
			(at 0 0 180)
			(layer "F.Fab")
			(effects
				(font
					(size 1.27 1.27)
				)
			)
		)
		(duplicate_pad_numbers_are_jumpers no)
		(fp_line
			(start 0.824992 1.050036)
			(end 0.254 1.050036)
			(stroke
				(width 0.1524)
				(type default)
			)
			(layer "F.SilkS")
		)
		(fp_line
			(start 0.824992 1.00584)
			(end 0.824992 1.050036)
			(stroke
				(width 0.1524)
				(type default)
			)
			(layer "F.SilkS")
		)
		(fp_line
			(start 0.824992 -1.050036)
			(end 0.824992 -1.00584)
			(stroke
				(width 0.1524)
				(type default)
			)
			(layer "F.SilkS")
		)
		(fp_line
			(start 0.254 -1.050036)
			(end 0.824992 -1.050036)
			(stroke
				(width 0.1524)
				(type default)
			)
			(layer "F.SilkS")
		)
		(fp_line
			(start -0.254 1.050036)
			(end -0.824992 1.050036)
			(stroke
				(width 0.1524)
				(type default)
			)
			(layer "F.SilkS")
		)
		(fp_line
			(start -0.824992 1.050036)
			(end -0.824992 1.00584)
			(stroke
				(width 0.1524)
				(type default)
			)
			(layer "F.SilkS")
		)
		(fp_line
			(start -0.824992 -1.01854)
			(end -0.824992 -1.050036)
			(stroke
				(width 0.1524)
				(type default)
			)
			(layer "F.SilkS")
		)
		(fp_line
			(start -0.824992 -1.050036)
			(end -0.254 -1.050036)
			(stroke
				(width 0.1524)
				(type default)
			)
			(layer "F.SilkS")
		)
		(fp_poly
			(pts
				(xy -1.969008 -0.411734) (xy -1.969008 -1.11379) (xy -1.266952 -0.762762)
			)
			(stroke
				(width 0)
				(type default)
			)
			(fill yes)
			(layer "F.SilkS")
		)
		(fp_line
			(start 0.824992 1.050036)
			(end -0.824992 1.050036)
			(stroke
				(width 0.1)
				(type default)
			)
			(layer "F.Fab")
		)
		(fp_line
			(start 0.824992 -1.050036)
			(end 0.824992 1.050036)
			(stroke
				(width 0.1)
				(type default)
			)
			(layer "F.Fab")
		)
		(fp_line
			(start -0.824992 1.050036)
			(end -0.824992 -1.050036)
			(stroke
				(width 0.1)
				(type default)
			)
			(layer "F.Fab")
		)
		(fp_line
			(start -0.824992 -1.050036)
			(end 0.824992 -1.050036)
			(stroke
				(width 0.1)
				(type default)
			)
			(layer "F.Fab")
		)
		(fp_poly
			(pts
				(xy -1.325372 -0.750062) (xy -2.027428 -0.399034) (xy -2.027428 -1.10109)
			)
			(stroke
				(width 0)
				(type default)
			)
			(fill yes)
			(layer "F.Fab")
		)
		(pad "1" smd rect
			(at -0.741172 -0.750062 270)
			(size 0.2794 0.8128)
			(layers "F.Cu" "F.Mask" "F.Paste")
			(net "JTAG_BMC_PLD_TDI")
		)
		(pad "2" smd rect
			(at -0.741172 -0.249936 270)
			(size 0.254 0.8128)
			(layers "F.Cu" "F.Mask" "F.Paste")
			(net "JTAG_BMC_DBP_TDI")
		)
		(pad "3" smd rect
			(at -0.741172 0.249936 270)
			(size 0.254 0.8128)
			(layers "F.Cu" "F.Mask" "F.Paste")
			(net "JTAG_BMC_PLD_TDO")
		)
		(pad "4" smd rect
			(at -0.741172 0.750062 270)
			(size 0.254 0.8128)
			(layers "F.Cu" "F.Mask" "F.Paste")
			(net "JTAG_BMC_DBP_TDO")
		)
		(pad "5" smd rect
			(at 0 0.94996 180)
			(size 0.254 0.8128)
			(layers "F.Cu" "F.Mask" "F.Paste")
			(net "GND")
		)
		(pad "6" smd rect
			(at 0.741172 0.750062 270)
			(size 0.254 0.8128)
			(layers "F.Cu" "F.Mask" "F.Paste")
			(net "JTAG_BMC_SW_TDO")
		)
		(pad "7" smd rect
			(at 0.741172 0.249936 270)
			(size 0.254 0.8128)
			(layers "F.Cu" "F.Mask" "F.Paste")
			(net "FM_JTAG_BMC_MUX_SEL")
		)
		(pad "8" smd rect
			(at 0.741172 -0.249936 270)
			(size 0.254 0.8128)
			(layers "F.Cu" "F.Mask" "F.Paste")
			(net "FM_JTAG_BMC_MUX_SEL")
		)
		(pad "9" smd rect
			(at 0.741172 -0.750062 270)
			(size 0.254 0.8128)
			(layers "F.Cu" "F.Mask" "F.Paste")
			(net "JTAG_BMC_SW_TDI")
		)
		(pad "10" smd rect
			(at 0 -0.94996 180)
			(size 0.254 0.8128)
			(layers "F.Cu" "F.Mask" "F.Paste")
			(net "P3V3_AUX")
		)
		(zone
			(layer "F.Cu")
			(hatch none 0.5)
			(connect_pads
				(clearance 0)
			)
			(min_thickness 0.25)
			(keepout
				(tracks not_allowed)
				(vias allowed)
				(pads allowed)
				(copperpour not_allowed)
				(footprints allowed)
			)
			(placement
				(enabled no)
				(sheetname "")
			)
			(fill
				(thermal_gap 0.5)
				(thermal_bridge_width 0.5)
				(island_removal_mode 0)
			)
			(polygon
				(pts
					(xy 128.114044 -76.631292) (xy 128.114044 -76.516992) (xy 127.567944 -76.516992) (xy 127.567944 -76.631292)
				)
			)
		)
	)
	(footprint ""
		(layer "F.Cu")
		(at 127.04064 -156.365448 180)
		(property "Reference" "R1493"
			(at 0 0 180)
			(layer "F.SilkS")
			(hide yes)
			(effects
				(font
					(size 1.27 1.27)
				)
			)
		)
		(property "Value" ""
			(at 0 0 180)
			(layer "F.Fab")
			(effects
				(font
					(size 1.27 1.27)
				)
			)
		)
		(duplicate_pad_numbers_are_jumpers no)
		(fp_line
			(start 0.7874 0.4064)
			(end -0.7874 0.4064)
			(stroke
				(width 0.1524)
				(type default)
			)
			(layer "F.SilkS")
		)
		(fp_line
			(start 0.7874 -0.4064)
			(end 0.7874 0.4064)
			(stroke
				(width 0.1524)
				(type default)
			)
			(layer "F.SilkS")
		)
		(fp_line
			(start -0.7874 0.4064)
			(end -0.7874 -0.4064)
			(stroke
				(width 0.1524)
				(type default)
			)
			(layer "F.SilkS")
		)
		(fp_line
			(start -0.7874 -0.4064)
			(end 0.7874 -0.4064)
			(stroke
				(width 0.1524)
				(type default)
			)
			(layer "F.SilkS")
		)
		(fp_line
			(start 0.67945 0.3048)
			(end 0.120396 0.3048)
			(stroke
				(width 0.1)
				(type default)
			)
			(layer "F.Fab")
		)
		(fp_line
			(start 0.67945 -0.3048)
			(end 0.67945 0.3048)
			(stroke
				(width 0.1)
				(type default)
			)
			(layer "F.Fab")
		)
		(fp_line
			(start 0.12065 -0.2794)
			(end 0.12065 -0.3048)
			(stroke
				(width 0.1)
				(type default)
			)
			(layer "F.Fab")
		)
		(fp_line
			(start 0.12065 -0.3048)
			(end 0.67945 -0.3048)
			(stroke
				(width 0.1)
				(type default)
			)
			(layer "F.Fab")
		)
		(fp_line
			(start 0.120396 0.3048)
			(end 0.120396 0.2794)
			(stroke
				(width 0.1)
				(type default)
			)
			(layer "F.Fab")
		)
		(fp_line
			(start 0.120396 0.2794)
			(end -0.12065 0.2794)
			(stroke
				(width 0.1)
				(type default)
			)
			(layer "F.Fab")
		)
		(fp_line
			(start -0.12065 0.3048)
			(end -0.67945 0.3048)
			(stroke
				(width 0.1)
				(type default)
			)
			(layer "F.Fab")
		)
		(fp_line
			(start -0.12065 0.2794)
			(end -0.12065 0.3048)
			(stroke
				(width 0.1)
				(type default)
			)
			(layer "F.Fab")
		)
		(fp_line
			(start -0.12065 -0.2794)
			(end 0.12065 -0.2794)
			(stroke
				(width 0.1)
				(type default)
			)
			(layer "F.Fab")
		)
		(fp_line
			(start -0.12065 -0.305054)
			(end -0.12065 -0.2794)
			(stroke
				(width 0.1)
				(type default)
			)
			(layer "F.Fab")
		)
		(fp_line
			(start -0.67945 0.3048)
			(end -0.67945 -0.305054)
			(stroke
				(width 0.1)
				(type default)
			)
			(layer "F.Fab")
		)
		(fp_line
			(start -0.67945 -0.305054)
			(end -0.12065 -0.305054)
			(stroke
				(width 0.1)
				(type default)
			)
			(layer "F.Fab")
		)
		(pad "1" smd circle
			(at -0.40005 0 180)
			(size 0 0)
			(layers "F.Cu" "F.Mask" "F.Paste")
			(net "P3V3_AUX")
		)
		(pad "2" smd circle
			(at 0.40005 0 180)
			(size 0 0)
			(layers "F.Cu" "F.Mask" "F.Paste")
			(net "PU_FORCE_PWRON")
		)
	)
)
